# SCM (Grand Teton) — schematic netlist excerpt (pin names and nets, part order shuffled) for the footprints in the layout excerpt that follows; sources: Cadence DE-HDL packaged netlist, KiCad conversion of 12092022_DA0F0TMDCD0_F0T_Management_Board_D_brd_V3_OCP.brd

R352  Q_RES  120 1% CHIP  pkg 0402LF  page 20 : A = M_BMC_DDR4_MA<1> ; B = P1V2_AUX
R191  Q_RES  1K 1% CHIP  pkg 0402LF  page 14 : A = P1V2_P1V0_I3C_VDDL1 ; B = I3C2_SPD_SDA

(kicad_pcb
	(version 20260206)
	(generator "pcbnew")
	(generator_version "10.0")
	(general
		(thickness 1.6)
		(legacy_teardrops no)
	)
	(paper "A4")
	(title_block
		(title "12092022_DA0F0TMDCD0_F0T_Management_Board_D_brd_V3_OCP.brd")
		(comment 1 "Grand Teton / footprints 955-956 of 1440")
	)
	(layers
		(0 "F.Cu" signal "TOP")
		(4 "In1.Cu" signal "GND")
		(6 "In2.Cu" signal "IN1")
		(8 "In3.Cu" signal "GND1")
		(10 "In4.Cu" signal "IN2")
		(12 "In5.Cu" signal "VCC")
		(14 "In6.Cu" signal "VCC1")
		(16 "In7.Cu" signal "IN3")
		(18 "In8.Cu" signal "GND2")
		(20 "In9.Cu" signal "IN4")
		(22 "In10.Cu" signal "GND3")
		(2 "B.Cu" signal "BOTTOM")
		(9 "F.Adhes" user "F.Adhesive")
		(11 "B.Adhes" user "B.Adhesive")
		(13 "F.Paste" user "Package Geometry/Pastemask Top")
		(15 "B.Paste" user "Package Geometry/Pastemask Bottom")
		(5 "F.SilkS" user "Ref Des/Silkscreen Top")
		(7 "B.SilkS" user "Ref Des/Silkscreen Bottom")
		(1 "F.Mask" user "Board Geometry/Soldermask Top")
		(3 "B.Mask" user "Board Geometry/Soldermask Bottom")
		(17 "Dwgs.User" user "User.Drawings")
		(19 "Cmts.User" user "User.Comments")
		(21 "Eco1.User" user "User.Eco1")
		(23 "Eco2.User" user "User.Eco2")
		(25 "Edge.Cuts" user "Board Geometry/Outline")
		(27 "Margin" user)
		(31 "F.CrtYd" user "Package Geometry/Place Bound Top")
		(29 "B.CrtYd" user "Package Geometry/Place Bound Bottom")
		(35 "F.Fab" user "Ref Des/Assembly Top")
		(33 "B.Fab" user "Ref Des/Assembly Bottom")
	)
	(footprint ""
		(layer "B.Cu")
		(at 85.29955 -40.363394 180)
		(property "Reference" "R352"
			(at 0 0 0)
			(layer "B.SilkS")
			(hide yes)
			(effects
				(font
					(size 1.27 1.27)
				)
				(justify mirror)
			)
		)
		(property "Value" ""
			(at 0 0 0)
			(layer "B.Fab")
			(effects
				(font
					(size 1.27 1.27)
				)
				(justify mirror)
			)
		)
		(duplicate_pad_numbers_are_jumpers no)
		(fp_line
			(start 0.7874 0.4064)
			(end 0.7874 -0.4064)
			(stroke
				(width 0.1524)
				(type default)
			)
			(layer "B.SilkS")
		)
		(fp_line
			(start 0.7874 -0.4064)
			(end -0.7874 -0.4064)
			(stroke
				(width 0.1524)
				(type default)
			)
			(layer "B.SilkS")
		)
		(fp_line
			(start -0.7874 0.4064)
			(end 0.7874 0.4064)
			(stroke
				(width 0.1524)
				(type default)
			)
			(layer "B.SilkS")
		)
		(fp_line
			(start -0.7874 -0.4064)
			(end -0.7874 0.4064)
			(stroke
				(width 0.1524)
				(type default)
			)
			(layer "B.SilkS")
		)
		(fp_line
			(start 0.67945 0.3048)
			(end 0.67945 -0.305054)
			(stroke
				(width 0.1)
				(type default)
			)
			(layer "B.Fab")
		)
		(fp_line
			(start 0.67945 -0.305054)
			(end 0.12065 -0.305054)
			(stroke
				(width 0.1)
				(type default)
			)
			(layer "B.Fab")
		)
		(fp_line
			(start 0.12065 0.3048)
			(end 0.67945 0.3048)
			(stroke
				(width 0.1)
				(type default)
			)
			(layer "B.Fab")
		)
		(fp_line
			(start 0.12065 0.2794)
			(end 0.12065 0.3048)
			(stroke
				(width 0.1)
				(type default)
			)
			(layer "B.Fab")
		)
		(fp_line
			(start 0.12065 -0.2794)
			(end -0.12065 -0.2794)
			(stroke
				(width 0.1)
				(type default)
			)
			(layer "B.Fab")
		)
		(fp_line
			(start 0.12065 -0.305054)
			(end 0.12065 -0.2794)
			(stroke
				(width 0.1)
				(type default)
			)
			(layer "B.Fab")
		)
		(fp_line
			(start -0.120396 0.3048)
			(end -0.120396 0.2794)
			(stroke
				(width 0.1)
				(type default)
			)
			(layer "B.Fab")
		)
		(fp_line
			(start -0.120396 0.2794)
			(end 0.12065 0.2794)
			(stroke
				(width 0.1)
				(type default)
			)
			(layer "B.Fab")
		)
		(fp_line
			(start -0.12065 -0.2794)
			(end -0.12065 -0.3048)
			(stroke
				(width 0.1)
				(type default)
			)
			(layer "B.Fab")
		)
		(fp_line
			(start -0.12065 -0.3048)
			(end -0.67945 -0.3048)
			(stroke
				(width 0.1)
				(type default)
			)
			(layer "B.Fab")
		)
		(fp_line
			(start -0.67945 0.3048)
			(end -0.120396 0.3048)
			(stroke
				(width 0.1)
				(type default)
			)
			(layer "B.Fab")
		)
		(fp_line
			(start -0.67945 -0.3048)
			(end -0.67945 0.3048)
			(stroke
				(width 0.1)
				(type default)
			)
			(layer "B.Fab")
		)
		(pad "1" smd circle
			(at 0.40005 0)
			(size 0 0)
			(layers "B.Cu" "B.Mask" "B.Paste")
			(net "M_BMC_DDR4_MA<1>")
		)
		(pad "2" smd circle
			(at -0.40005 0)
			(size 0 0)
			(layers "B.Cu" "B.Mask" "B.Paste")
			(net "P1V2_AUX")
		)
	)
	(footprint ""
		(layer "B.Cu")
		(at 43.163236 -65.743582 -90)
		(property "Reference" "R191"
			(at 0 0 90)
			(layer "B.SilkS")
			(hide yes)
			(effects
				(font
					(size 1.27 1.27)
				)
				(justify mirror)
			)
		)
		(property "Value" ""
			(at 0 0 90)
			(layer "B.Fab")
			(effects
				(font
					(size 1.27 1.27)
				)
				(justify mirror)
			)
		)
		(duplicate_pad_numbers_are_jumpers no)
		(fp_line
			(start -0.7874 0.4064)
			(end 0.7874 0.4064)
			(stroke
				(width 0.1524)
				(type default)
			)
			(layer "B.SilkS")
		)
		(fp_line
			(start 0.7874 0.4064)
			(end 0.7874 -0.4064)
			(stroke
				(width 0.1524)
				(type default)
			)
			(layer "B.SilkS")
		)
		(fp_line
			(start -0.7874 -0.4064)
			(end -0.7874 0.4064)
			(stroke
				(width 0.1524)
				(type default)
			)
			(layer "B.SilkS")
		)
		(fp_line
			(start 0.7874 -0.4064)
			(end -0.7874 -0.4064)
			(stroke
				(width 0.1524)
				(type default)
			)
			(layer "B.SilkS")
		)
		(fp_line
			(start -0.67945 0.3048)
			(end -0.120396 0.3048)
			(stroke
				(width 0.1)
				(type default)
			)
			(layer "B.Fab")
		)
		(fp_line
			(start -0.120396 0.3048)
			(end -0.120396 0.2794)
			(stroke
				(width 0.1)
				(type default)
			)
			(layer "B.Fab")
		)
		(fp_line
			(start 0.12065 0.3048)
			(end 0.67945 0.3048)
			(stroke
				(width 0.1)
				(type default)
			)
			(layer "B.Fab")
		)
		(fp_line
			(start 0.67945 0.3048)
			(end 0.67945 -0.305054)
			(stroke
				(width 0.1)
				(type default)
			)
			(layer "B.Fab")
		)
		(fp_line
			(start -0.120396 0.2794)
			(end 0.12065 0.2794)
			(stroke
				(width 0.1)
				(type default)
			)
			(layer "B.Fab")
		)
		(fp_line
			(start 0.12065 0.2794)
			(end 0.12065 0.3048)
			(stroke
				(width 0.1)
				(type default)
			)
			(layer "B.Fab")
		)
		(fp_line
			(start -0.12065 -0.2794)
			(end -0.12065 -0.3048)
			(stroke
				(width 0.1)
				(type default)
			)
			(layer "B.Fab")
		)
		(fp_line
			(start 0.12065 -0.2794)
			(end -0.12065 -0.2794)
			(stroke
				(width 0.1)
				(type default)
			)
			(layer "B.Fab")
		)
		(fp_line
			(start -0.67945 -0.3048)
			(end -0.67945 0.3048)
			(stroke
				(width 0.1)
				(type default)
			)
			(layer "B.Fab")
		)
		(fp_line
			(start -0.12065 -0.3048)
			(end -0.67945 -0.3048)
			(stroke
				(width 0.1)
				(type default)
			)
			(layer "B.Fab")
		)
		(fp_line
			(start 0.12065 -0.305054)
			(end 0.12065 -0.2794)
			(stroke
				(width 0.1)
				(type default)
			)
			(layer "B.Fab")
		)
		(fp_line
			(start 0.67945 -0.305054)
			(end 0.12065 -0.305054)
			(stroke
				(width 0.1)
				(type default)
			)
			(layer "B.Fab")
		)
		(pad "1" smd circle
			(at 0.40005 0 90)
			(size 0 0)
			(layers "B.Cu" "B.Mask" "B.Paste")
			(net "P1V2_P1V0_I3C_VDDL1")
		)
		(pad "2" smd circle
			(at -0.40005 0 90)
			(size 0 0)
			(layers "B.Cu" "B.Mask" "B.Paste")
			(net "I3C2_SPD_SDA")
		)
	)
)
